%FSTAX25Y25*%
%MOIN*%
%SFA1B1*%

%IPPOS*%
%ADD41R,0.028000X0.165000*%
%ADD42R,0.028000X0.126000*%
%ADD131R,0.025200X0.026770*%
%LNtimecard-dc-beta-v1-1*%
%LPD*%
G54D41*
X0309646Y001378D03*
X0187599D03*
X0183661D03*
X0215158D03*
X0211221D03*
X0270275D03*
X0301771D03*
X0297834D03*
X0286023D03*
X0266338D03*
X0282086D03*
X025059D03*
X0246654D03*
X0238779D03*
X0234842D03*
X0219094D03*
X0195473D03*
X0199409D03*
X0203346D03*
X0207283D03*
X0258465D03*
X0242717D03*
X0230906D03*
X027815D03*
X0293898D03*
X0274213D03*
X0305709D03*
X0289961D03*
X0262402D03*
X0254527D03*
X0191535D03*
G54D42*
X0179725Y001573D03*
G54D131*
X0301984Y0032913D03*
Y0036299D03*
X0234984D03*
Y0032913D03*
X0238984D03*
Y0036299D03*
X0246884D03*
Y0032913D03*
X0251184D03*
Y0036299D03*
X0266484Y0032913D03*
Y0036299D03*
X0270484Y0032913D03*
Y0036299D03*
X0281984Y0032913D03*
Y0036299D03*
X0285484D03*
Y0032913D03*
X0297984D03*
Y0036299D03*
M02*